(kicad_pcb
	(version 20260206)
	(generator "pcbnew")
	(generator_version "10.0")
	(general
		(thickness 1.6)
		(legacy_teardrops no)
	)
	(paper "A4")
	(title_block
		(title "dpb — 14545-sa.0730WZS0815.brd")
		(comment 1 "Honey Badger (Wiwynn) / footprints 460-461 of 1066")
	)
	(layers
		(0 "F.Cu" signal "TOP")
		(4 "In1.Cu" signal "L2GND")
		(6 "In2.Cu" signal "L3")
		(8 "In3.Cu" signal "L4VCC")
		(10 "In4.Cu" signal "L5VCC")
		(12 "In5.Cu" signal "L6")
		(14 "In6.Cu" signal "L7GND")
		(2 "B.Cu" signal "BOTTOM")
		(9 "F.Adhes" user "F.Adhesive")
		(11 "B.Adhes" user "B.Adhesive")
		(13 "F.Paste" user "Package Geometry/Pastemask Top")
		(15 "B.Paste" user "Package Geometry/Pastemask Bottom")
		(5 "F.SilkS" user "Ref Des/Silkscreen Top")
		(7 "B.SilkS" user "Ref Des/Silkscreen Bottom")
		(1 "F.Mask" user "Board Geometry/Soldermask Top")
		(3 "B.Mask" user "Board Geometry/Soldermask Bottom")
		(17 "Dwgs.User" user "User.Drawings")
		(19 "Cmts.User" user "User.Comments")
		(21 "Eco1.User" user "User.Eco1")
		(23 "Eco2.User" user "User.Eco2")
		(25 "Edge.Cuts" user "Board Geometry/Outline")
		(27 "Margin" user)
		(31 "F.CrtYd" user "Package Geometry/Place Bound Top")
		(29 "B.CrtYd" user "Package Geometry/Place Bound Bottom")
		(35 "F.Fab" user "Ref Des/Assembly Top")
		(33 "B.Fab" user "Ref Des/Assembly Bottom")
	)
	(footprint ""
		(layer "F.Cu")
		(at 227.499926 -67.669918 90)
		(property "Reference" "SKT5"
			(at 0 0 90)
			(layer "F.SilkS")
			(hide yes)
			(effects
				(font
					(size 1.27 1.27)
				)
			)
		)
		(property "Value" "SKT-SATA14P-15P-12-GP"
			(at -22.6187 8.1788 90)
			(unlocked yes)
			(layer "F.Fab")
			(hide yes)
			(effects
				(font
					(size 1.016 1.016)
					(thickness 0.1524)
				)
			)
		)
		(property "Device Type" "87945-1001"
			(at -22.6187 6.6548 90)
			(unlocked yes)
			(layer "F.Fab")
			(hide yes)
			(effects
				(font
					(size 1.016 1.016)
					(thickness 0.1524)
				)
			)
		)
		(duplicate_pad_numbers_are_jumpers no)
		(fp_line
			(start -15.3924 -5.8547)
			(end -16.3576 -5.8547)
			(stroke
				(width 0.3302)
				(type default)
			)
			(layer "F.SilkS")
		)
		(fp_line
			(start 20.4724 -5.7658)
			(end 20.4724 -2.3114)
			(stroke
				(width 0.1524)
				(type default)
			)
			(layer "F.SilkS")
		)
		(fp_line
			(start -20.4724 -5.7658)
			(end 20.4724 -5.7658)
			(stroke
				(width 0.1524)
				(type default)
			)
			(layer "F.SilkS")
		)
		(fp_line
			(start 23.7617 -2.3114)
			(end 23.7617 2.3114)
			(stroke
				(width 0.1524)
				(type default)
			)
			(layer "F.SilkS")
		)
		(fp_line
			(start 20.4724 -2.3114)
			(end 23.7617 -2.3114)
			(stroke
				(width 0.1524)
				(type default)
			)
			(layer "F.SilkS")
		)
		(fp_line
			(start -20.4724 -2.3114)
			(end -20.4724 -5.7658)
			(stroke
				(width 0.1524)
				(type default)
			)
			(layer "F.SilkS")
		)
		(fp_line
			(start -23.7617 -2.3114)
			(end -20.4724 -2.3114)
			(stroke
				(width 0.1524)
				(type default)
			)
			(layer "F.SilkS")
		)
		(fp_line
			(start 23.117556 -0.5461)
			(end 23.117556 0.5461)
			(stroke
				(width 0.3048)
				(type default)
			)
			(layer "F.SilkS")
		)
		(fp_line
			(start -20.882356 -0.5461)
			(end -20.882356 0.5461)
			(stroke
				(width 0.3048)
				(type default)
			)
			(layer "F.SilkS")
		)
		(fp_line
			(start 20.882356 0.5461)
			(end 20.882356 -0.5461)
			(stroke
				(width 0.3048)
				(type default)
			)
			(layer "F.SilkS")
		)
		(fp_line
			(start -23.117556 0.5461)
			(end -23.117556 -0.5461)
			(stroke
				(width 0.3048)
				(type default)
			)
			(layer "F.SilkS")
		)
		(fp_line
			(start 23.7617 2.3114)
			(end 20.4724 2.3114)
			(stroke
				(width 0.1524)
				(type default)
			)
			(layer "F.SilkS")
		)
		(fp_line
			(start 20.4724 2.3114)
			(end 20.4724 9.652)
			(stroke
				(width 0.1524)
				(type default)
			)
			(layer "F.SilkS")
		)
		(fp_line
			(start -20.4724 2.3114)
			(end -23.7617 2.3114)
			(stroke
				(width 0.1524)
				(type default)
			)
			(layer "F.SilkS")
		)
		(fp_line
			(start -23.7617 2.3114)
			(end -23.7617 -2.3114)
			(stroke
				(width 0.1524)
				(type default)
			)
			(layer "F.SilkS")
		)
		(fp_line
			(start 17.8435 7.9502)
			(end -17.8435 7.9502)
			(stroke
				(width 0.1524)
				(type default)
			)
			(layer "F.SilkS")
		)
		(fp_line
			(start -17.8435 7.9502)
			(end -17.8435 9.652)
			(stroke
				(width 0.1524)
				(type default)
			)
			(layer "F.SilkS")
		)
		(fp_line
			(start 20.4724 9.652)
			(end 17.8435 9.652)
			(stroke
				(width 0.1524)
				(type default)
			)
			(layer "F.SilkS")
		)
		(fp_line
			(start 17.8435 9.652)
			(end 17.8435 7.9502)
			(stroke
				(width 0.1524)
				(type default)
			)
			(layer "F.SilkS")
		)
		(fp_line
			(start -17.8435 9.652)
			(end -20.4724 9.652)
			(stroke
				(width 0.1524)
				(type default)
			)
			(layer "F.SilkS")
		)
		(fp_line
			(start -20.4724 9.652)
			(end -20.4724 2.3114)
			(stroke
				(width 0.1524)
				(type default)
			)
			(layer "F.SilkS")
		)
		(fp_arc
			(start 20.882356 -0.5461)
			(mid 21.999956 -1.6637)
			(end 23.117556 -0.5461)
			(stroke
				(width 0.3048)
				(type default)
			)
			(layer "F.SilkS")
		)
		(fp_arc
			(start -23.117556 -0.5461)
			(mid -21.999956 -1.6637)
			(end -20.882356 -0.5461)
			(stroke
				(width 0.3048)
				(type default)
			)
			(layer "F.SilkS")
		)
		(fp_arc
			(start 23.117556 0.5461)
			(mid 21.999956 1.6637)
			(end 20.882356 0.5461)
			(stroke
				(width 0.3048)
				(type default)
			)
			(layer "F.SilkS")
		)
		(fp_arc
			(start -20.882356 0.5461)
			(mid -21.999956 1.6637)
			(end -23.117556 0.5461)
			(stroke
				(width 0.3048)
				(type default)
			)
			(layer "F.SilkS")
		)
		(fp_poly
			(pts
				(xy -15.87119 -5.838698) (xy -15.23619 -6.473698) (xy -16.50619 -6.473698)
			)
			(stroke
				(width 0)
				(type default)
			)
			(fill yes)
			(layer "F.SilkS")
		)
		(fp_poly
			(pts
				(xy -20.2184 -5.5118) (xy 20.2184 -5.5118) (xy 20.2184 -2.0574) (xy 23.5077 -2.0574) (xy 23.5077 2.0574)
				(xy 20.2184 2.0574) (xy 20.2184 9.398) (xy 18.0975 9.398) (xy 18.0975 7.6962) (xy -18.0975 7.6962)
				(xy -18.0975 9.398) (xy -20.2184 9.398) (xy -20.2184 2.0574) (xy -23.5077 2.0574) (xy -23.5077 -2.0574)
				(xy -20.2184 -2.0574)
			)
			(stroke
				(width 0)
				(type default)
			)
			(fill no)
			(layer "F.CrtYd")
		)
		(fp_poly
			(pts
				(xy -20.2184 -5.5118) (xy -20.2184 -6.0198) (xy -20.7264 -6.0198) (xy -20.7264 -2.5654) (xy -24.0157 -2.5654)
				(xy -24.0157 2.5654) (xy -20.7264 2.5654) (xy -20.7264 9.906) (xy -17.5895 9.906) (xy -17.5895 8.2042)
				(xy 17.5895 8.2042) (xy 17.5895 9.906) (xy 20.7264 9.906) (xy 20.7264 2.5654) (xy 24.0157 2.5654)
				(xy 24.0157 -2.5654) (xy 20.7264 -2.5654) (xy 20.7264 -6.0198) (xy -20.21586 -6.0198) (xy -20.21586 -5.5118)
				(xy 20.2184 -5.5118) (xy 20.2184 -2.0574) (xy 23.5077 -2.0574) (xy 23.5077 2.0574) (xy 20.2184 2.0574)
				(xy 20.2184 9.398) (xy 18.0975 9.398) (xy 18.0975 7.6962) (xy -18.0975 7.6962) (xy -18.0975 9.398)
				(xy -20.2184 9.398) (xy -20.2184 2.0574) (xy -23.5077 2.0574) (xy -23.5077 -2.0574) (xy -20.2184 -2.0574)
			)
			(stroke
				(width 0)
				(type default)
			)
			(fill no)
			(layer "F.CrtYd")
		)
		(fp_poly
			(pts
				(xy -20.7264 -6.0198) (xy -20.7264 -2.5654) (xy -24.0157 -2.5654) (xy -24.0157 2.5654) (xy -20.7264 2.5654)
				(xy -20.7264 9.906) (xy -17.5895 9.906) (xy -17.5895 8.2042) (xy 17.5895 8.2042) (xy 17.5895 9.906)
				(xy 20.7264 9.906) (xy 20.7264 2.5654) (xy 24.0157 2.5654) (xy 24.0157 -2.5654) (xy 20.7264 -2.5654)
				(xy 20.7264 -6.0198)
			)
			(stroke
				(width 0)
				(type default)
			)
			(fill no)
			(layer "F.Fab")
		)
		(pad "" np_thru_hole circle
			(at -18.999962 -2.350008 90)
			(size 0.254 0.254)
			(drill 1.8542)
			(layers "*.Cu" "*.Mask")
			(clearance 1.1557)
			(thermal_gap 1.1557)
		)
		(pad "" np_thru_hole circle
			(at 18.999962 -2.350008 90)
			(size 0.254 0.254)
			(drill 1.8542)
			(layers "*.Cu" "*.Mask")
			(clearance 1.1557)
			(thermal_gap 1.1557)
		)
		(pad "H1" thru_hole oval
			(at -21.999956 0 90)
			(size 1.524 2.6162)
			(drill oval 0.8128 1.905)
			(layers "*.Cu" "*.Mask")
			(remove_unused_layers no)
			(net "GND")
			(clearance 0.1524)
			(thermal_gap 0.1524)
		)
		(pad "H2" thru_hole oval
			(at 21.999956 0 90)
			(size 1.524 2.6162)
			(drill oval 0.8128 1.905)
			(layers "*.Cu" "*.Mask")
			(remove_unused_layers no)
			(net "GND")
			(clearance 0.1524)
			(thermal_gap 0.1524)
		)
		(pad "P1" smd rect
			(at -1.89992 -4.249928 90)
			(size 0.6604 2.3876)
			(layers "F.Cu" "F.Mask" "F.Paste")
			(net "Net_25")
		)
		(pad "P2" smd rect
			(at -0.62992 -4.249928 90)
			(size 0.6604 2.3876)
			(layers "F.Cu" "F.Mask" "F.Paste")
			(net "Net_24")
		)
		(pad "P3" smd rect
			(at 0.64008 -4.249928 90)
			(size 0.6604 2.3876)
			(layers "F.Cu" "F.Mask" "F.Paste")
			(net "Net_23")
		)
		(pad "P4" smd rect
			(at 1.91008 -4.249928 90)
			(size 0.6604 2.3876)
			(layers "F.Cu" "F.Mask" "F.Paste")
			(net "GND")
		)
		(pad "P5" smd rect
			(at 3.18008 -4.249928 90)
			(size 0.6604 2.3876)
			(layers "F.Cu" "F.Mask" "F.Paste")
			(net "HDD_PRSNT_NET4")
		)
		(pad "P6" smd rect
			(at 4.45008 -4.249928 90)
			(size 0.6604 2.3876)
			(layers "F.Cu" "F.Mask" "F.Paste")
			(net "GND")
		)
		(pad "P7" smd rect
			(at 5.72008 -4.249928 90)
			(size 0.6604 2.3876)
			(layers "F.Cu" "F.Mask" "F.Paste")
			(net "5V_PRE_4")
		)
		(pad "P8" smd rect
			(at 6.99008 -4.249928 90)
			(size 0.6604 2.3876)
			(layers "F.Cu" "F.Mask" "F.Paste")
			(net "P5V_HDD4")
		)
		(pad "P9" smd rect
			(at 8.26008 -4.249928 90)
			(size 0.6604 2.3876)
			(layers "F.Cu" "F.Mask" "F.Paste")
			(net "P5V_HDD4")
		)
		(pad "P10" smd rect
			(at 9.53008 -4.249928 90)
			(size 0.6604 2.3876)
			(layers "F.Cu" "F.Mask" "F.Paste")
			(net "GND")
		)
		(pad "P11" smd rect
			(at 10.80008 -4.249928 90)
			(size 0.6604 2.3876)
			(layers "F.Cu" "F.Mask" "F.Paste")
			(net "ACT_HDD4")
		)
		(pad "P12" smd rect
			(at 12.07008 -4.249928 90)
			(size 0.6604 2.3876)
			(layers "F.Cu" "F.Mask" "F.Paste")
			(net "GND")
		)
		(pad "P13" smd rect
			(at 13.34008 -4.249928 90)
			(size 0.6604 2.3876)
			(layers "F.Cu" "F.Mask" "F.Paste")
			(net "12V_PRE_4")
		)
		(pad "P14" smd rect
			(at 14.61008 -4.249928 90)
			(size 0.6604 2.3876)
			(layers "F.Cu" "F.Mask" "F.Paste")
			(net "P12V_HDD4")
		)
		(pad "P15" smd rect
			(at 15.88008 -4.249928 90)
			(size 0.6604 2.3876)
			(layers "F.Cu" "F.Mask" "F.Paste")
			(net "P12V_HDD4")
		)
		(pad "S1" smd rect
			(at -15.86992 -4.249928 90)
			(size 0.6604 2.3876)
			(layers "F.Cu" "F.Mask" "F.Paste")
			(net "GND")
		)
		(pad "S2" smd rect
			(at -14.59992 -4.249928 90)
			(size 0.6604 2.3876)
			(layers "F.Cu" "F.Mask" "F.Paste")
			(net "SAS2X28_A_HDD4_TX_+")
		)
		(pad "S3" smd rect
			(at -13.32992 -4.249928 90)
			(size 0.6604 2.3876)
			(layers "F.Cu" "F.Mask" "F.Paste")
			(net "SAS2X28_A_HDD4_TX_-")
		)
		(pad "S4" smd rect
			(at -12.05992 -4.249928 90)
			(size 0.6604 2.3876)
			(layers "F.Cu" "F.Mask" "F.Paste")
			(net "GND")
		)
		(pad "S5" smd rect
			(at -10.78992 -4.249928 90)
			(size 0.6604 2.3876)
			(layers "F.Cu" "F.Mask" "F.Paste")
			(net "SAS2X28_DRIVE_RX_N_A4")
		)
		(pad "S6" smd rect
			(at -9.51992 -4.249928 90)
			(size 0.6604 2.3876)
			(layers "F.Cu" "F.Mask" "F.Paste")
			(net "SAS2X28_DRIVE_RX_P_A4")
		)
		(pad "S7" smd rect
			(at -8.24992 -4.249928 90)
			(size 0.6604 2.3876)
			(layers "F.Cu" "F.Mask" "F.Paste")
			(net "GND")
		)
		(pad "S8" smd rect
			(at -7.480046 -2.100072 90)
			(size 0.508 1.905)
			(layers "F.Cu" "F.Mask" "F.Paste")
			(net "GND")
		)
		(pad "S9" smd rect
			(at -6.679946 -2.100072 90)
			(size 0.508 1.905)
			(layers "F.Cu" "F.Mask" "F.Paste")
			(net "SAS2X28_B_HDD4_TX_+")
		)
		(pad "S10" smd rect
			(at -5.8801 -2.100072 90)
			(size 0.508 1.905)
			(layers "F.Cu" "F.Mask" "F.Paste")
			(net "SAS2X28_B_HDD4_TX_-")
		)
		(pad "S11" smd rect
			(at -5.08 -2.100072 90)
			(size 0.508 1.905)
			(layers "F.Cu" "F.Mask" "F.Paste")
			(net "GND")
		)
		(pad "S12" smd rect
			(at -4.2799 -2.100072 90)
			(size 0.508 1.905)
			(layers "F.Cu" "F.Mask" "F.Paste")
			(net "SAS2X28_DRIVE_RX_N_B4")
		)
		(pad "S13" smd rect
			(at -3.480054 -2.100072 90)
			(size 0.508 1.905)
			(layers "F.Cu" "F.Mask" "F.Paste")
			(net "SAS2X28_DRIVE_RX_P_B4")
		)
		(pad "S14" smd rect
			(at -2.679954 -2.100072 90)
			(size 0.508 1.905)
			(layers "F.Cu" "F.Mask" "F.Paste")
			(net "GND")
		)
		(zone
			(layers "F.Cu" "B.Cu" "In1.Cu" "In2.Cu" "In3.Cu" "In4.Cu" "In5.Cu" "In6.Cu")
			(hatch none 0.5)
			(connect_pads
				(clearance 0)
			)
			(min_thickness 0.25)
			(keepout
				(tracks not_allowed)
				(vias allowed)
				(pads allowed)
				(copperpour not_allowed)
				(footprints allowed)
			)
			(placement
				(enabled no)
				(sheetname "")
			)
			(fill
				(thermal_gap 0.5)
				(thermal_bridge_width 0.5)
				(island_removal_mode 0)
			)
			(polygon
				(pts
					(arc
						(start 226.381818 -86.66988)
						(mid 223.918018 -86.66988)
						(end 226.381818 -86.66988)
					)
				)
			)
		)
		(zone
			(layers "F.Cu" "B.Cu" "In1.Cu" "In2.Cu" "In3.Cu" "In4.Cu" "In5.Cu" "In6.Cu")
			(hatch none 0.5)
			(connect_pads
				(clearance 0)
			)
			(min_thickness 0.25)
			(keepout
				(tracks not_allowed)
				(vias allowed)
				(pads allowed)
				(copperpour not_allowed)
				(footprints allowed)
			)
			(placement
				(enabled no)
				(sheetname "")
			)
			(fill
				(thermal_gap 0.5)
				(thermal_bridge_width 0.5)
				(island_removal_mode 0)
			)
			(polygon
				(pts
					(arc
						(start 226.381818 -48.669956)
						(mid 223.918018 -48.669956)
						(end 226.381818 -48.669956)
					)
				)
			)
		)
	)
	(footprint ""
		(layer "F.Cu")
		(at 236.067346 -40.259 -90)
		(property "Reference" "R492"
			(at 0 0 270)
			(layer "F.SilkS")
			(hide yes)
			(effects
				(font
					(size 1.27 1.27)
				)
			)
		)
		(property "Value" "1KR2F-3-GP"
			(at 0.064008 -3.993896 270)
			(unlocked yes)
			(layer "F.Fab")
			(hide yes)
			(effects
				(font
					(size 1.016 1.016)
					(thickness 0.1524)
				)
			)
		)
		(property "Device Type" "R402H16"
			(at 0.064008 -5.517896 270)
			(unlocked yes)
			(layer "F.Fab")
			(hide yes)
			(effects
				(font
					(size 1.016 1.016)
					(thickness 0.1524)
				)
			)
		)
		(duplicate_pad_numbers_are_jumpers no)
		(fp_line
			(start -0.508 -0.9398)
			(end -0.508 0.9398)
			(stroke
				(width 0.1524)
				(type default)
			)
			(layer "F.SilkS")
		)
		(fp_line
			(start 0.508 -0.9398)
			(end -0.508 -0.9398)
			(stroke
				(width 0.1524)
				(type default)
			)
			(layer "F.SilkS")
		)
		(fp_rect
			(start -0.508 0.9398)
			(end 0.508 -0.9398)
			(stroke
				(width 0)
				(type default)
			)
			(fill no)
			(layer "F.CrtYd")
		)
		(fp_rect
			(start -0.508 0.9398)
			(end 0.508 -0.9398)
			(stroke
				(width 0)
				(type default)
			)
			(fill no)
			(layer "F.Fab")
		)
		(pad "1" smd custom
			(at 0 -0.4445 270)
			(size 0.1397 0.1397)
			(layers "F.Cu" "F.Mask" "F.Paste")
			(net "FLT_HDD4_B")
			(options
				(clearance outline)
				(anchor circle)
			)
			(primitives
				(gr_poly
					(pts
						(arc
							(start -0.1778 -0.2794)
							(mid -0.249642 -0.249642)
							(end -0.2794 -0.1778)
						)
						(arc
							(start -0.2794 0.1778)
							(mid -0.249642 0.249642)
							(end -0.1778 0.2794)
						)
						(arc
							(start 0.1778 0.2794)
							(mid 0.249642 0.249642)
							(end 0.2794 0.1778)
						)
						(arc
							(start 0.2794 -0.1778)
							(mid 0.249642 -0.249642)
							(end 0.1778 -0.2794)
						)
					)
					(width 0)
					(fill yes)
				)
			)
		)
		(pad "2" smd custom
			(at 0 0.4445 270)
			(size 0.1397 0.1397)
			(layers "F.Cu" "F.Mask" "F.Paste")
			(net "FLT_HDD4_DRIVE")
			(options
				(clearance outline)
				(anchor circle)
			)
			(primitives
				(gr_poly
					(pts
						(arc
							(start -0.1778 -0.2794)
							(mid -0.249642 -0.249642)
							(end -0.2794 -0.1778)
						)
						(arc
							(start -0.2794 0.1778)
							(mid -0.249642 0.249642)
							(end -0.1778 0.2794)
						)
						(arc
							(start 0.1778 0.2794)
							(mid 0.249642 0.249642)
							(end 0.2794 0.1778)
						)
						(arc
							(start 0.2794 -0.1778)
							(mid 0.249642 -0.249642)
							(end 0.1778 -0.2794)
						)
					)
					(width 0)
					(fill yes)
				)
			)
		)
	)
)
